# TIMECARD (Time Appliance Project (Time Card)) — schematic netlist excerpt (pin names and nets, part order shuffled) for the footprints in the layout excerpt that follows; sources: Cadence DE-HDL packaged netlist, KiCad conversion of R4006-B0001-02_R01.brd

C160  CAPACITOR  4.7UF 6.3V 20%  pkg SMC_0402R_H026  page 14 : \1\ = XP2R5V_FPGA ; \2\ = SG
R229  RESISTOR  4.7KOHM 1%  pkg SMC_0402R_H016  page 31 : \1\ = XP3R3V_FPGA ; \2\ = UNNAMED_515_CAPACITOR_I138_1

(kicad_pcb
	(version 20260206)
	(generator "pcbnew")
	(generator_version "10.0")
	(general
		(thickness 1.6)
		(legacy_teardrops no)
	)
	(paper "A4")
	(title_block
		(title "timecard-production-celestica-r4006 — R4006-B0001-02_R01.brd")
		(comment 1 "Time Appliance Project (Time Card) / footprints 726-727 of 1113")
	)
	(layers
		(0 "F.Cu" signal "TOP")
		(4 "In1.Cu" signal "L02_GND1")
		(6 "In2.Cu" signal "L03_SIG1")
		(8 "In3.Cu" signal "L04_GND2")
		(10 "In4.Cu" signal "L05_VCC1")
		(12 "In5.Cu" signal "L06_VCC2")
		(14 "In6.Cu" signal "L07_GND3")
		(16 "In7.Cu" signal "L08_SIG2")
		(18 "In8.Cu" signal "L09_GND4")
		(2 "B.Cu" signal "BOTTOM")
		(9 "F.Adhes" user "F.Adhesive")
		(11 "B.Adhes" user "B.Adhesive")
		(13 "F.Paste" user "Package Geometry/Pastemask Top")
		(15 "B.Paste" user "Package Geometry/Pastemask Bottom")
		(5 "F.SilkS" user "Ref Des/Silkscreen Top")
		(7 "B.SilkS" user "Ref Des/Silkscreen Bottom")
		(1 "F.Mask" user "Board Geometry/Soldermask Top")
		(3 "B.Mask" user "Board Geometry/Soldermask Bottom")
		(17 "Dwgs.User" user "User.Drawings")
		(19 "Cmts.User" user "User.Comments")
		(21 "Eco1.User" user "User.Eco1")
		(23 "Eco2.User" user "User.Eco2")
		(25 "Edge.Cuts" user "Board Geometry/Outline")
		(27 "Margin" user)
		(31 "F.CrtYd" user "Package Geometry/Place Bound Top")
		(29 "B.CrtYd" user "Package Geometry/Place Bound Bottom")
		(35 "F.Fab" user "Ref Des/Assembly Top")
		(33 "B.Fab" user "Ref Des/Assembly Bottom")
	)
	(footprint ""
		(layer "B.Cu")
		(at 141.097 -15.9766 -90)
		(property "Reference" "R229"
			(at -5.7404 0.16637 270)
			(unlocked yes)
			(layer "B.SilkS")
			(effects
				(font
					(size 0.7874 0.5842)
					(thickness 0.1524)
				)
				(justify mirror)
			)
		)
		(property "Value" "VAL*"
			(at -0.02032 2.13233 270)
			(unlocked yes)
			(layer "B.Fab")
			(hide yes)
			(effects
				(font
					(size 0.7874 0.5842)
					(thickness 0.1524)
				)
				(justify mirror)
			)
		)
		(property "Tolerance" "TOL*"
			(at -0.044704 3.05435 270)
			(unlocked yes)
			(layer "Cmts.User")
			(hide yes)
			(effects
				(font
					(size 0.7874 0.5842)
					(thickness 0.1524)
				)
				(justify mirror)
			)
		)
		(property "User Part Number" "PARTNUM*"
			(at -0.02032 4.024884 270)
			(unlocked yes)
			(layer "Cmts.User")
			(hide yes)
			(effects
				(font
					(size 0.7874 0.5842)
					(thickness 0.1524)
				)
				(justify mirror)
			)
		)
		(property "Device Type" "RESISTOR-G155-14701-01,4.7KOHMA"
			(at -0.008382 1.210564 270)
			(unlocked yes)
			(layer "B.Fab")
			(hide yes)
			(effects
				(font
					(size 0.7874 0.5842)
					(thickness 0.1524)
				)
				(justify mirror)
			)
		)
		(duplicate_pad_numbers_are_jumpers no)
		(fp_line
			(start -1.143 0.5588)
			(end -1.143 -0.5588)
			(stroke
				(width 0.1)
				(type default)
			)
			(layer "B.SilkS")
		)
		(fp_line
			(start 1.143 0.5588)
			(end -1.143 0.5588)
			(stroke
				(width 0.1)
				(type default)
			)
			(layer "B.SilkS")
		)
		(fp_line
			(start -1.143 -0.5588)
			(end 1.143 -0.5588)
			(stroke
				(width 0.1)
				(type default)
			)
			(layer "B.SilkS")
		)
		(fp_line
			(start 1.143 -0.5588)
			(end 1.143 0.5588)
			(stroke
				(width 0.1)
				(type default)
			)
			(layer "B.SilkS")
		)
		(fp_rect
			(start -1.143 -0.5588)
			(end 1.143 0.5588)
			(stroke
				(width 0)
				(type default)
			)
			(fill no)
			(layer "B.CrtYd")
		)
		(fp_line
			(start -0.508 0.3048)
			(end -0.508 -0.3048)
			(stroke
				(width 0.1)
				(type default)
			)
			(layer "B.Fab")
		)
		(fp_line
			(start 0.508 0.3048)
			(end -0.508 0.3048)
			(stroke
				(width 0.1)
				(type default)
			)
			(layer "B.Fab")
		)
		(fp_line
			(start -0.508 -0.3048)
			(end 0.508 -0.3048)
			(stroke
				(width 0.1)
				(type default)
			)
			(layer "B.Fab")
		)
		(fp_line
			(start 0.508 -0.3048)
			(end 0.508 0.3048)
			(stroke
				(width 0.1)
				(type default)
			)
			(layer "B.Fab")
		)
		(pad "1" smd rect
			(at 0.5334 0 90)
			(size 0.7112 0.6096)
			(layers "B.Cu" "B.Mask" "B.Paste")
			(net "XP3R3V_FPGA")
		)
		(pad "2" smd rect
			(at -0.5334 0 90)
			(size 0.7112 0.6096)
			(layers "B.Cu" "B.Mask" "B.Paste")
			(net "UNNAMED_515_CAPACITOR_I138_1")
		)
		(zone
			(layer "B.Cu")
			(hatch none 0.5)
			(connect_pads
				(clearance 0)
			)
			(min_thickness 0.25)
			(keepout
				(tracks allowed)
				(vias not_allowed)
				(pads allowed)
				(copperpour not_allowed)
				(footprints allowed)
			)
			(placement
				(enabled no)
				(sheetname "")
			)
			(fill
				(thermal_gap 0.5)
				(thermal_bridge_width 0.5)
				(island_removal_mode 0)
			)
			(polygon
				(pts
					(xy 141.4018 -16.0528) (xy 140.7922 -16.0528) (xy 140.7922 -15.9004) (xy 141.4018 -15.9004)
				)
			)
		)
	)
	(footprint ""
		(layer "B.Cu")
		(at 114.847116 -35.322764 -90)
		(property "Reference" "C160"
			(at 0.778764 0.959866 270)
			(unlocked yes)
			(layer "B.SilkS")
			(effects
				(font
					(size 0.635 0.4064)
					(thickness 0.1524)
				)
				(justify mirror)
			)
		)
		(property "Value" "VAL*"
			(at 0 3.718306 270)
			(unlocked yes)
			(layer "B.Fab")
			(hide yes)
			(effects
				(font
					(size 0.7874 0.5842)
					(thickness 0.127)
				)
				(justify mirror)
			)
		)
		(property "Device Type" "CAPACITOR-G105-0F475-BM,4.7UF,A"
			(at 0 1.432306 270)
			(unlocked yes)
			(layer "B.Fab")
			(hide yes)
			(effects
				(font
					(size 0.7874 0.5842)
					(thickness 0.127)
				)
				(justify mirror)
			)
		)
		(property "User Part Number" "PARTNUM*"
			(at 0 2.575306 270)
			(unlocked yes)
			(layer "Cmts.User")
			(hide yes)
			(effects
				(font
					(size 0.7874 0.5842)
					(thickness 0.127)
				)
				(justify mirror)
			)
		)
		(property "Tolerance" "TOL*"
			(at 0 4.861306 270)
			(unlocked yes)
			(layer "Cmts.User")
			(hide yes)
			(effects
				(font
					(size 0.7874 0.5842)
					(thickness 0.127)
				)
				(justify mirror)
			)
		)
		(duplicate_pad_numbers_are_jumpers no)
		(fp_line
			(start -0.970026 0.4699)
			(end 0.970026 0.4699)
			(stroke
				(width 0.1)
				(type default)
			)
			(layer "B.SilkS")
		)
		(fp_line
			(start 0.970026 0.4699)
			(end 0.970026 -0.4699)
			(stroke
				(width 0.1)
				(type default)
			)
			(layer "B.SilkS")
		)
		(fp_line
			(start -0.970026 -0.4699)
			(end -0.970026 0.4699)
			(stroke
				(width 0.1)
				(type default)
			)
			(layer "B.SilkS")
		)
		(fp_line
			(start 0.970026 -0.4699)
			(end -0.970026 -0.4699)
			(stroke
				(width 0.1)
				(type default)
			)
			(layer "B.SilkS")
		)
		(fp_poly
			(pts
				(xy 0.970026 0.4699) (xy -0.970026 0.4699) (xy -0.970026 -0.4699) (xy 0.970026 -0.4699)
			)
			(stroke
				(width 0)
				(type default)
			)
			(fill no)
			(layer "B.CrtYd")
		)
		(fp_line
			(start -0.508 0.3048)
			(end 0.508 0.3048)
			(stroke
				(width 0.1)
				(type default)
			)
			(layer "B.Fab")
		)
		(fp_line
			(start 0.508 0.3048)
			(end 0.508 -0.3048)
			(stroke
				(width 0.1)
				(type default)
			)
			(layer "B.Fab")
		)
		(fp_line
			(start -0.508 -0.3048)
			(end -0.508 0.3048)
			(stroke
				(width 0.1)
				(type default)
			)
			(layer "B.Fab")
		)
		(fp_line
			(start 0.508 -0.3048)
			(end -0.508 -0.3048)
			(stroke
				(width 0.1)
				(type default)
			)
			(layer "B.Fab")
		)
		(pad "1" smd circle
			(at 0.500126 0 90)
			(size 0.635 0.635)
			(layers "B.Cu" "B.Mask" "B.Paste")
			(net "XP2R5V_FPGA")
		)
		(pad "2" smd circle
			(at -0.500126 0 90)
			(size 0.635 0.635)
			(layers "B.Cu" "B.Mask" "B.Paste")
			(net "SG")
		)
	)
)
